G04*
G04 #@! TF.GenerationSoftware,Altium Limited,Altium Designer,23.6.0 (18)*
G04*
G04 Layer_Physical_Order=5*
G04 Layer_Color=16440176*
%FSLAX44Y44*%
%MOMM*%
G71*
G04*
G04 #@! TF.SameCoordinates,0D6CC9A4-690D-4EF8-AA6E-9FB67146BD04*
G04*
G04*
G04 #@! TF.FilePolarity,Positive*
G04*
G01*
G75*
%ADD76R,2.0200X2.0200*%
%ADD77C,2.0200*%
%ADD78C,2.0900*%
%ADD79C,5.3000*%
%ADD80C,0.6000*%
G36*
X503922Y502958D02*
X503922Y5000D01*
X503921Y4999D01*
X503290Y4368D01*
X502957Y4078D01*
X5000Y4078D01*
X4919D01*
X4078Y5042D01*
X4078Y502953D01*
X4746Y503699D01*
X5000Y503921D01*
X503000Y503922D01*
X503081D01*
X503922Y502958D01*
D02*
G37*
%LPC*%
G36*
X193522Y499450D02*
X190478D01*
X187493Y498856D01*
X184682Y497692D01*
X182151Y496001D01*
X179999Y493849D01*
X178308Y491318D01*
X177687Y489819D01*
X176313D01*
X175692Y491318D01*
X174001Y493849D01*
X171849Y496001D01*
X169318Y497692D01*
X166507Y498856D01*
X163522Y499450D01*
X160478D01*
X157493Y498856D01*
X154682Y497692D01*
X152151Y496001D01*
X149999Y493849D01*
X148308Y491318D01*
X147144Y488507D01*
X146550Y485522D01*
Y482478D01*
X147144Y479493D01*
X148308Y476682D01*
X149999Y474151D01*
X152151Y471999D01*
X154682Y470308D01*
X157493Y469144D01*
X160478Y468550D01*
X163522D01*
X166507Y469144D01*
X169318Y470308D01*
X171849Y471999D01*
X174001Y474151D01*
X175692Y476682D01*
X176313Y478181D01*
X177687D01*
X178308Y476682D01*
X179999Y474151D01*
X182151Y471999D01*
X184682Y470308D01*
X187493Y469144D01*
X190478Y468550D01*
X193522D01*
X196507Y469144D01*
X199318Y470308D01*
X201849Y471999D01*
X204001Y474151D01*
X205692Y476682D01*
X206856Y479493D01*
X207450Y482478D01*
Y485522D01*
X206856Y488507D01*
X205692Y491318D01*
X204001Y493849D01*
X201849Y496001D01*
X199318Y497692D01*
X196507Y498856D01*
X193522Y499450D01*
D02*
G37*
G36*
X242495Y483750D02*
X240505D01*
X238668Y482989D01*
X237261Y481582D01*
X236500Y479745D01*
Y477755D01*
X237261Y475918D01*
X238668Y474511D01*
X240505Y473750D01*
X242495D01*
X244332Y474511D01*
X245739Y475918D01*
X246500Y477755D01*
Y479745D01*
X245739Y481582D01*
X244332Y482989D01*
X242495Y483750D01*
D02*
G37*
G36*
X133639Y496450D02*
X130361D01*
X127194Y495602D01*
X124355Y493963D01*
X122037Y491645D01*
X120398Y488806D01*
X119550Y485639D01*
Y482361D01*
X120398Y479194D01*
X122037Y476356D01*
X124355Y474038D01*
X127194Y472398D01*
X130361Y471550D01*
X133639D01*
X136805Y472398D01*
X139644Y474038D01*
X141962Y476356D01*
X143602Y479194D01*
X144450Y482361D01*
Y485639D01*
X143602Y488806D01*
X141962Y491645D01*
X139644Y493963D01*
X136805Y495602D01*
X133639Y496450D01*
D02*
G37*
G36*
X103639D02*
X100361D01*
X97194Y495602D01*
X94355Y493963D01*
X92037Y491645D01*
X90398Y488806D01*
X89550Y485639D01*
Y482361D01*
X90398Y479194D01*
X92037Y476356D01*
X94355Y474038D01*
X97194Y472398D01*
X100361Y471550D01*
X103639D01*
X106805Y472398D01*
X109644Y474038D01*
X111962Y476356D01*
X113602Y479194D01*
X114450Y482361D01*
Y485639D01*
X113602Y488806D01*
X111962Y491645D01*
X109644Y493963D01*
X106805Y495602D01*
X103639Y496450D01*
D02*
G37*
G36*
X73639D02*
X70361D01*
X67194Y495602D01*
X64356Y493963D01*
X62038Y491645D01*
X60399Y488806D01*
X59550Y485639D01*
Y482361D01*
X60399Y479194D01*
X62038Y476356D01*
X64356Y474038D01*
X67194Y472398D01*
X70361Y471550D01*
X73639D01*
X76806Y472398D01*
X79644Y474038D01*
X81962Y476356D01*
X83602Y479194D01*
X84450Y482361D01*
Y485639D01*
X83602Y488806D01*
X81962Y491645D01*
X79644Y493963D01*
X76806Y495602D01*
X73639Y496450D01*
D02*
G37*
G36*
X49000Y469912D02*
X45986Y469105D01*
X43024Y467395D01*
X40605Y464976D01*
X38895Y462014D01*
X38088Y459000D01*
X49000D01*
Y469912D01*
D02*
G37*
G36*
X140744Y468508D02*
X138755D01*
X136918Y467747D01*
X135511Y466340D01*
X134750Y464503D01*
Y462514D01*
X135511Y460676D01*
X136918Y459269D01*
X138755Y458508D01*
X140744D01*
X142582Y459269D01*
X143989Y460676D01*
X144750Y462514D01*
Y464503D01*
X143989Y466340D01*
X142582Y467747D01*
X140744Y468508D01*
D02*
G37*
G36*
X53000Y469912D02*
Y459000D01*
X63912D01*
X63863Y459186D01*
X64017Y459366D01*
X65749Y459430D01*
X66168Y459011D01*
X68005Y458250D01*
X69995D01*
X71832Y459011D01*
X73239Y460418D01*
X74000Y462255D01*
Y464245D01*
X73239Y466082D01*
X71832Y467489D01*
X69995Y468250D01*
X68005D01*
X66168Y467489D01*
X64761Y466082D01*
X64000Y464245D01*
Y463003D01*
X62730Y462663D01*
X61395Y464976D01*
X58976Y467395D01*
X56014Y469105D01*
X53000Y469912D01*
D02*
G37*
G36*
X49000Y455000D02*
X38088D01*
X38895Y451986D01*
X40605Y449024D01*
X43024Y446605D01*
X45986Y444895D01*
X49000Y444088D01*
Y455000D01*
D02*
G37*
G36*
X63912D02*
X53000D01*
Y444088D01*
X56014Y444895D01*
X58976Y446605D01*
X61395Y449024D01*
X63105Y451986D01*
X63912Y455000D01*
D02*
G37*
G36*
X458522Y472450D02*
X455478D01*
X452493Y471856D01*
X449682Y470692D01*
X447151Y469001D01*
X444999Y466849D01*
X443308Y464318D01*
X442144Y461507D01*
X441550Y458522D01*
Y455478D01*
X442144Y452493D01*
X443308Y449682D01*
X444999Y447151D01*
X447151Y444999D01*
X449682Y443308D01*
X452493Y442144D01*
X455478Y441550D01*
X458522D01*
X461507Y442144D01*
X464318Y443308D01*
X466849Y444999D01*
X469001Y447151D01*
X470692Y449682D01*
X471856Y452493D01*
X472450Y455478D01*
Y458522D01*
X471856Y461507D01*
X470692Y464318D01*
X469001Y466849D01*
X466849Y469001D01*
X464318Y470692D01*
X461507Y471856D01*
X458522Y472450D01*
D02*
G37*
G36*
X415019Y472500D02*
X410981D01*
X407020Y471712D01*
X403290Y470167D01*
X399932Y467923D01*
X397077Y465068D01*
X394833Y461710D01*
X393288Y457980D01*
X392500Y454019D01*
Y449981D01*
X393288Y446020D01*
X394833Y442290D01*
X397077Y438932D01*
X399932Y436077D01*
X403290Y433833D01*
X407020Y432288D01*
X410981Y431500D01*
X415019D01*
X418980Y432288D01*
X422710Y433833D01*
X426068Y436077D01*
X428923Y438932D01*
X431167Y442290D01*
X432712Y446020D01*
X433500Y449981D01*
Y454019D01*
X432712Y457980D01*
X431167Y461710D01*
X428923Y465068D01*
X426068Y467923D01*
X422710Y470167D01*
X418980Y471712D01*
X415019Y472500D01*
D02*
G37*
G36*
X235392Y427690D02*
X233403D01*
X231566Y426929D01*
X230159Y425522D01*
X229398Y423685D01*
Y421696D01*
X230159Y419858D01*
X231566Y418451D01*
X233403Y417690D01*
X235392D01*
X237230Y418451D01*
X238637Y419858D01*
X239398Y421696D01*
Y423685D01*
X238637Y425522D01*
X237230Y426929D01*
X235392Y427690D01*
D02*
G37*
G36*
X97019Y457500D02*
X92981D01*
X89020Y456712D01*
X85289Y455167D01*
X81932Y452923D01*
X79077Y450068D01*
X76833Y446710D01*
X75288Y442980D01*
X74500Y439019D01*
Y434981D01*
X75288Y431020D01*
X76833Y427290D01*
X79077Y423932D01*
X81932Y421077D01*
X85289Y418833D01*
X89020Y417288D01*
X92981Y416500D01*
X97019D01*
X100980Y417288D01*
X104710Y418833D01*
X108068Y421077D01*
X110923Y423932D01*
X113167Y427290D01*
X114712Y431020D01*
X115500Y434981D01*
Y439019D01*
X114712Y442980D01*
X113167Y446710D01*
X110923Y450068D01*
X108068Y452923D01*
X104710Y455167D01*
X100980Y456712D01*
X97019Y457500D01*
D02*
G37*
G36*
X224367Y420288D02*
X222378D01*
X220540Y419527D01*
X219134Y418120D01*
X218373Y416283D01*
Y414294D01*
X219134Y412456D01*
X220540Y411049D01*
X222378Y410288D01*
X224367D01*
X226205Y411049D01*
X227611Y412456D01*
X228373Y414294D01*
Y416283D01*
X227611Y418120D01*
X226205Y419527D01*
X224367Y420288D01*
D02*
G37*
G36*
X18780Y402960D02*
X16791D01*
X14953Y402199D01*
X13547Y400792D01*
X12785Y398955D01*
Y396965D01*
X13547Y395128D01*
X14953Y393721D01*
X16791Y392960D01*
X18780D01*
X20618Y393721D01*
X22024Y395128D01*
X22785Y396965D01*
Y398955D01*
X22024Y400792D01*
X20618Y402199D01*
X18780Y402960D01*
D02*
G37*
G36*
X346264Y398919D02*
X344275D01*
X342437Y398158D01*
X341031Y396751D01*
X340269Y394914D01*
Y392924D01*
X341031Y391087D01*
X342437Y389680D01*
X344275Y388919D01*
X346264D01*
X348102Y389680D01*
X349508Y391087D01*
X350269Y392924D01*
Y394914D01*
X349508Y396751D01*
X348102Y398158D01*
X346264Y398919D01*
D02*
G37*
G36*
X316245Y397363D02*
X314256D01*
X312418Y396602D01*
X311011Y395196D01*
X310250Y393358D01*
Y391369D01*
X311011Y389531D01*
X312418Y388124D01*
X314256Y387363D01*
X316245D01*
X318082Y388124D01*
X319489Y389531D01*
X320250Y391369D01*
Y393358D01*
X319489Y395196D01*
X318082Y396602D01*
X316245Y397363D01*
D02*
G37*
G36*
X392022Y366264D02*
X390033D01*
X388195Y365503D01*
X386789Y364096D01*
X386028Y362258D01*
Y360269D01*
X386789Y358432D01*
X388195Y357025D01*
X390033Y356264D01*
X392022D01*
X393860Y357025D01*
X395266Y358432D01*
X396028Y360269D01*
Y362258D01*
X395266Y364096D01*
X393860Y365503D01*
X392022Y366264D01*
D02*
G37*
G36*
X18495Y372710D02*
X16505D01*
X14668Y371949D01*
X13261Y370542D01*
X12500Y368704D01*
Y366715D01*
X13261Y364878D01*
X14668Y363471D01*
X15148Y363272D01*
Y361898D01*
X14668Y361699D01*
X13261Y360292D01*
X12500Y358455D01*
Y356465D01*
X13261Y354628D01*
X14668Y353221D01*
X16505Y352460D01*
X18495D01*
X20332Y353221D01*
X21739Y354628D01*
X22500Y356465D01*
Y358455D01*
X21739Y360292D01*
X20332Y361699D01*
X19852Y361898D01*
Y363272D01*
X20332Y363471D01*
X21739Y364878D01*
X22500Y366715D01*
Y368704D01*
X21739Y370542D01*
X20332Y371949D01*
X18495Y372710D01*
D02*
G37*
G36*
X96604Y358378D02*
X94615D01*
X92777Y357617D01*
X91371Y356210D01*
X90610Y354372D01*
Y352383D01*
X91371Y350546D01*
X92777Y349139D01*
X94615Y348378D01*
X96604D01*
X98442Y349139D01*
X99848Y350546D01*
X100610Y352383D01*
Y354372D01*
X99848Y356210D01*
X98442Y357617D01*
X96604Y358378D01*
D02*
G37*
G36*
X355745Y344500D02*
X353755D01*
X351918Y343739D01*
X350511Y342332D01*
X349750Y340495D01*
Y338505D01*
X350511Y336668D01*
X351918Y335261D01*
X353755Y334500D01*
X355745D01*
X357582Y335261D01*
X358989Y336668D01*
X359750Y338505D01*
Y340495D01*
X358989Y342332D01*
X357582Y343739D01*
X355745Y344500D01*
D02*
G37*
G36*
X221963Y344000D02*
X219974D01*
X218136Y343239D01*
X216730Y341832D01*
X215968Y339995D01*
Y338005D01*
X216730Y336168D01*
X218136Y334761D01*
X219974Y334000D01*
X221963D01*
X223801Y334761D01*
X225207Y336168D01*
X225968Y338005D01*
Y339995D01*
X225207Y341832D01*
X223801Y343239D01*
X221963Y344000D01*
D02*
G37*
G36*
X467243Y377500D02*
X462757D01*
X458326Y376798D01*
X454060Y375412D01*
X450063Y373375D01*
X446433Y370739D01*
X443261Y367566D01*
X440625Y363937D01*
X438588Y359940D01*
X437202Y355674D01*
X436500Y351243D01*
Y346757D01*
X437202Y342326D01*
X438588Y338060D01*
X440625Y334063D01*
X443261Y330434D01*
X446433Y327261D01*
X450063Y324625D01*
X454060Y322588D01*
X458326Y321202D01*
X462757Y320500D01*
X467243D01*
X471674Y321202D01*
X475940Y322588D01*
X479937Y324625D01*
X483567Y327261D01*
X486739Y330434D01*
X489375Y334063D01*
X491412Y338060D01*
X492798Y342326D01*
X493500Y346757D01*
Y351243D01*
X492798Y355674D01*
X491412Y359940D01*
X489375Y363937D01*
X486739Y367566D01*
X483567Y370739D01*
X479937Y373375D01*
X475940Y375412D01*
X471674Y376798D01*
X467243Y377500D01*
D02*
G37*
G36*
X245239Y297311D02*
X243250D01*
X241412Y296550D01*
X240006Y295143D01*
X239245Y293305D01*
Y291316D01*
X240006Y289479D01*
X241412Y288072D01*
X243250Y287311D01*
X245239D01*
X247077Y288072D01*
X248483Y289479D01*
X249245Y291316D01*
Y293305D01*
X248483Y295143D01*
X247077Y296550D01*
X245239Y297311D01*
D02*
G37*
G36*
X404053Y282430D02*
X401947D01*
X399912Y281885D01*
X398088Y280832D01*
X396599Y279343D01*
X395545Y277518D01*
X395000Y275484D01*
Y273377D01*
X395545Y271343D01*
X396599Y269518D01*
X398088Y268029D01*
X399912Y266976D01*
X401947Y266430D01*
X404053D01*
X406088Y266976D01*
X407912Y268029D01*
X409402Y269518D01*
X410455Y271343D01*
X411000Y273377D01*
Y275484D01*
X410455Y277518D01*
X409402Y279343D01*
X407912Y280832D01*
X406088Y281885D01*
X404053Y282430D01*
D02*
G37*
G36*
X459000Y266912D02*
Y256000D01*
X469912D01*
X469105Y259014D01*
X467395Y261976D01*
X464976Y264395D01*
X462014Y266105D01*
X459000Y266912D01*
D02*
G37*
G36*
X455000Y266912D02*
X451986Y266105D01*
X449024Y264395D01*
X446605Y261976D01*
X444895Y259014D01*
X444088Y256000D01*
X455000D01*
Y266912D01*
D02*
G37*
G36*
X244495Y262561D02*
X242505D01*
X240668Y261800D01*
X239261Y260393D01*
X238500Y258556D01*
Y256566D01*
X239261Y254729D01*
X240668Y253322D01*
X242505Y252561D01*
X244495D01*
X246332Y253322D01*
X247739Y254729D01*
X248500Y256566D01*
Y258556D01*
X247739Y260393D01*
X246332Y261800D01*
X244495Y262561D01*
D02*
G37*
G36*
X469912Y252000D02*
X459000D01*
Y241088D01*
X462014Y241895D01*
X464976Y243605D01*
X467395Y246024D01*
X469105Y248986D01*
X469912Y252000D01*
D02*
G37*
G36*
X455000D02*
X444088D01*
X444895Y248986D01*
X446605Y246024D01*
X449024Y243605D01*
X451986Y241895D01*
X455000Y241088D01*
Y252000D01*
D02*
G37*
G36*
X259933Y214744D02*
X257944D01*
X256106Y213983D01*
X254700Y212576D01*
X253939Y210738D01*
Y208749D01*
X254700Y206912D01*
X256106Y205505D01*
X257944Y204744D01*
X259933D01*
X261771Y205505D01*
X263178Y206912D01*
X263939Y208749D01*
Y210738D01*
X263178Y212576D01*
X261771Y213983D01*
X259933Y214744D01*
D02*
G37*
G36*
X244933D02*
X242944D01*
X241106Y213983D01*
X239700Y212576D01*
X238939Y210738D01*
Y208749D01*
X239700Y206912D01*
X241106Y205505D01*
X242944Y204744D01*
X244933D01*
X246771Y205505D01*
X248178Y206912D01*
X248939Y208749D01*
Y210738D01*
X248178Y212576D01*
X246771Y213983D01*
X244933Y214744D01*
D02*
G37*
G36*
X229418D02*
X227429D01*
X225591Y213983D01*
X224185Y212576D01*
X223424Y210738D01*
Y208749D01*
X224185Y206912D01*
X225591Y205505D01*
X227429Y204744D01*
X229418D01*
X231256Y205505D01*
X232662Y206912D01*
X233424Y208749D01*
Y210738D01*
X232662Y212576D01*
X231256Y213983D01*
X229418Y214744D01*
D02*
G37*
G36*
X315995Y208311D02*
X314006D01*
X312168Y207550D01*
X310761Y206143D01*
X310000Y204306D01*
Y202316D01*
X310761Y200479D01*
X312168Y199072D01*
X314006Y198311D01*
X315995D01*
X317832Y199072D01*
X319239Y200479D01*
X320000Y202316D01*
Y204306D01*
X319239Y206143D01*
X317832Y207550D01*
X315995Y208311D01*
D02*
G37*
G36*
X280201Y195705D02*
X278212D01*
X276374Y194944D01*
X274967Y193537D01*
X274206Y191700D01*
Y189711D01*
X274967Y187873D01*
X276374Y186466D01*
X278212Y185705D01*
X280201D01*
X282038Y186466D01*
X283445Y187873D01*
X284206Y189711D01*
Y191700D01*
X283445Y193537D01*
X282038Y194944D01*
X280201Y195705D01*
D02*
G37*
G36*
X225124Y193721D02*
X223134D01*
X221297Y192960D01*
X219890Y191553D01*
X219129Y189715D01*
Y187726D01*
X219890Y185889D01*
X221297Y184482D01*
X223134Y183721D01*
X225124D01*
X226961Y184482D01*
X228368Y185889D01*
X229129Y187726D01*
Y189715D01*
X228368Y191553D01*
X226961Y192960D01*
X225124Y193721D01*
D02*
G37*
G36*
X57650Y191550D02*
X54771Y190779D01*
X51889Y189114D01*
X49535Y186761D01*
X47871Y183879D01*
X47620Y182941D01*
X46350Y183108D01*
Y191100D01*
X22150D01*
Y166900D01*
X46350D01*
Y174892D01*
X47620Y175059D01*
X47871Y174121D01*
X49535Y171239D01*
X51889Y168885D01*
X54771Y167221D01*
X57650Y166450D01*
Y179000D01*
Y191550D01*
D02*
G37*
G36*
X61650D02*
Y181000D01*
X72200D01*
X71429Y183879D01*
X69764Y186761D01*
X67411Y189114D01*
X64529Y190779D01*
X61650Y191550D01*
D02*
G37*
G36*
X244933Y187955D02*
X242944D01*
X241106Y187194D01*
X239700Y185787D01*
X238939Y183950D01*
Y181961D01*
X239700Y180123D01*
X241106Y178716D01*
X242944Y177955D01*
X244933D01*
X246771Y178716D01*
X248178Y180123D01*
X248939Y181961D01*
Y183950D01*
X248178Y185787D01*
X246771Y187194D01*
X244933Y187955D01*
D02*
G37*
G36*
X259933Y187705D02*
X257944D01*
X256106Y186944D01*
X254700Y185537D01*
X253939Y183700D01*
Y181710D01*
X254700Y179873D01*
X256106Y178466D01*
X257944Y177705D01*
X259933D01*
X261771Y178466D01*
X263178Y179873D01*
X263939Y181710D01*
Y183700D01*
X263178Y185537D01*
X261771Y186944D01*
X259933Y187705D01*
D02*
G37*
G36*
X404053Y193091D02*
X401947D01*
X399912Y192545D01*
X398088Y191492D01*
X396599Y190003D01*
X395545Y188179D01*
X395000Y186144D01*
Y184037D01*
X395545Y182003D01*
X396599Y180179D01*
X398088Y178689D01*
X399912Y177636D01*
X401947Y177091D01*
X404053D01*
X406088Y177636D01*
X407912Y178689D01*
X409402Y180179D01*
X410455Y182003D01*
X411000Y184037D01*
Y186144D01*
X410455Y188179D01*
X409402Y190003D01*
X407912Y191492D01*
X406088Y192545D01*
X404053Y193091D01*
D02*
G37*
G36*
X212995Y179955D02*
X211005D01*
X209168Y179194D01*
X207761Y177787D01*
X207000Y175950D01*
Y173960D01*
X207761Y172123D01*
X209168Y170716D01*
X211005Y169955D01*
X212995D01*
X214832Y170716D01*
X216239Y172123D01*
X217000Y173960D01*
Y175950D01*
X216239Y177787D01*
X214832Y179194D01*
X212995Y179955D01*
D02*
G37*
G36*
X72200Y177000D02*
X61650D01*
Y166450D01*
X64529Y167221D01*
X67411Y168885D01*
X69764Y171239D01*
X71429Y174121D01*
X72200Y177000D01*
D02*
G37*
G36*
X352156Y131070D02*
X350167D01*
X348329Y130309D01*
X347171Y129150D01*
X346082Y130239D01*
X344245Y131000D01*
X342255D01*
X340418Y130239D01*
X339011Y128832D01*
X338250Y126995D01*
Y125005D01*
X339011Y123168D01*
X340418Y121761D01*
X340648Y121666D01*
Y120291D01*
X339918Y119989D01*
X338511Y118582D01*
X337750Y116745D01*
Y114755D01*
X338511Y112918D01*
X339918Y111511D01*
X340804Y111144D01*
Y109769D01*
X339738Y109328D01*
X338331Y107921D01*
X337570Y106083D01*
Y104094D01*
X338331Y102256D01*
X339738Y100850D01*
X339968Y100755D01*
Y99380D01*
X339238Y99078D01*
X337831Y97671D01*
X337070Y95833D01*
Y93844D01*
X337831Y92007D01*
X339238Y90600D01*
X340717Y89987D01*
X340844Y88669D01*
X340843Y88665D01*
X340418Y88489D01*
X339011Y87082D01*
X338250Y85245D01*
Y83255D01*
X339011Y81418D01*
X340418Y80011D01*
X340648Y79916D01*
Y78541D01*
X339918Y78239D01*
X338511Y76832D01*
X337750Y74995D01*
Y73005D01*
X338511Y71168D01*
X339918Y69761D01*
X340804Y69394D01*
Y68019D01*
X339738Y67578D01*
X338331Y66171D01*
X337570Y64333D01*
Y62344D01*
X338331Y60507D01*
X339738Y59100D01*
X339968Y59005D01*
Y57630D01*
X339238Y57328D01*
X337831Y55921D01*
X337070Y54083D01*
Y52094D01*
X337831Y50257D01*
X339238Y48850D01*
X339044Y47555D01*
X338750Y46845D01*
Y44856D01*
X339511Y43018D01*
X340918Y41611D01*
X341148Y41516D01*
Y40142D01*
X340418Y39839D01*
X339011Y38433D01*
X338250Y36595D01*
Y34606D01*
X339011Y32768D01*
X340418Y31361D01*
X342255Y30600D01*
X344245D01*
X346082Y31361D01*
X347489Y32768D01*
X348247Y34598D01*
X348917Y34320D01*
X350906D01*
X352743Y35081D01*
X354150Y36488D01*
X354245Y36718D01*
X355620D01*
X355922Y35988D01*
X357329Y34581D01*
X359167Y33820D01*
X361156D01*
X362994Y34581D01*
X364400Y35988D01*
X365161Y37826D01*
Y39815D01*
X364400Y41652D01*
X362994Y43059D01*
X361156Y43820D01*
X359167D01*
X357329Y43059D01*
X355922Y41652D01*
X355827Y41422D01*
X354452D01*
X354150Y42152D01*
X352743Y43559D01*
X350906Y44320D01*
X349903D01*
X348847Y44811D01*
X348750Y45493D01*
Y45897D01*
X349111Y46914D01*
X349923Y47070D01*
X351156D01*
X352994Y47831D01*
X354400Y49238D01*
X354495Y49468D01*
X355870D01*
X356172Y48738D01*
X357579Y47331D01*
X359417Y46570D01*
X361406D01*
X363243Y47331D01*
X364650Y48738D01*
X365411Y50575D01*
Y52565D01*
X364650Y54402D01*
X363243Y55809D01*
X361406Y56570D01*
X359417D01*
X357579Y55809D01*
X356172Y54402D01*
X356077Y54172D01*
X354702D01*
X354400Y54902D01*
X352994Y56309D01*
X351156Y57070D01*
X349167D01*
X347329Y56309D01*
X346836Y55816D01*
X346309Y55921D01*
X344902Y57328D01*
X344672Y57423D01*
Y58798D01*
X345402Y59100D01*
X346676Y60374D01*
X347775Y59275D01*
X349612Y58513D01*
X351601D01*
X353439Y59275D01*
X354846Y60681D01*
X354941Y60911D01*
X356316D01*
X356618Y60181D01*
X358025Y58775D01*
X359862Y58014D01*
X361851D01*
X363689Y58775D01*
X365096Y60181D01*
X365857Y62019D01*
Y64008D01*
X365096Y65846D01*
X363689Y67252D01*
X361851Y68014D01*
X359862D01*
X358025Y67252D01*
X356618Y65846D01*
X356523Y65616D01*
X355148D01*
X354846Y66346D01*
X353439Y67752D01*
X351601Y68513D01*
X349612D01*
X347775Y67752D01*
X346501Y66479D01*
X345402Y67578D01*
X344516Y67945D01*
Y69320D01*
X345582Y69761D01*
X346096Y70275D01*
X347329Y70831D01*
X348024Y70543D01*
X349167Y70070D01*
X351156D01*
X352994Y70831D01*
X354400Y72238D01*
X354495Y72468D01*
X355870D01*
X356172Y71738D01*
X357579Y70331D01*
X359417Y69570D01*
X361406D01*
X363243Y70331D01*
X364650Y71738D01*
X365411Y73576D01*
Y75565D01*
X364650Y77402D01*
X363243Y78809D01*
X361406Y79570D01*
X359417D01*
X357579Y78809D01*
X356172Y77402D01*
X356077Y77172D01*
X354702D01*
X354400Y77902D01*
X352994Y79309D01*
X351156Y80070D01*
X349167D01*
X347329Y79309D01*
X346816Y78796D01*
X346500Y78653D01*
X346311Y78731D01*
X346198Y79363D01*
X346216Y80145D01*
X347489Y81418D01*
X348250Y83255D01*
Y84636D01*
X349372Y85512D01*
X349423Y85524D01*
X349917Y85320D01*
X351906D01*
X353744Y86081D01*
X355150Y87488D01*
X355245Y87718D01*
X356620D01*
X356922Y86988D01*
X358329Y85581D01*
X360167Y84820D01*
X362156D01*
X363993Y85581D01*
X365400Y86988D01*
X366161Y88826D01*
Y90815D01*
X365400Y92652D01*
X363993Y94059D01*
X362156Y94820D01*
X360167D01*
X358329Y94059D01*
X356922Y92652D01*
X356827Y92422D01*
X355452D01*
X355150Y93152D01*
X353744Y94559D01*
X351906Y95320D01*
X349917D01*
X348340Y94667D01*
X347457Y95044D01*
X347070Y95346D01*
Y95833D01*
X346309Y97671D01*
X344950Y99030D01*
X344937Y99986D01*
X344951Y100346D01*
X345562Y100723D01*
X346876Y100350D01*
X346922Y100238D01*
X348329Y98831D01*
X350167Y98070D01*
X352156D01*
X353993Y98831D01*
X355400Y100238D01*
X355495Y100468D01*
X356870D01*
X357172Y99738D01*
X358579Y98331D01*
X360417Y97570D01*
X362406D01*
X364244Y98331D01*
X365650Y99738D01*
X366411Y101575D01*
Y103565D01*
X365650Y105402D01*
X364244Y106809D01*
X362406Y107570D01*
X360417D01*
X358579Y106809D01*
X357172Y105402D01*
X357077Y105172D01*
X355702D01*
X355400Y105902D01*
X353993Y107309D01*
X352156Y108070D01*
X350167D01*
X348421Y107347D01*
X348025Y107265D01*
X346996Y107469D01*
X346809Y107921D01*
X345402Y109328D01*
X344516Y109695D01*
Y111069D01*
X345582Y111511D01*
X346087Y112015D01*
X347332Y111768D01*
X347368Y111681D01*
X348775Y110275D01*
X350612Y109514D01*
X352601D01*
X354439Y110275D01*
X355846Y111681D01*
X355941Y111911D01*
X357316D01*
X357618Y111181D01*
X359025Y109775D01*
X360862Y109014D01*
X362851D01*
X364689Y109775D01*
X366096Y111181D01*
X366857Y113019D01*
Y115008D01*
X366096Y116846D01*
X364689Y118252D01*
X362851Y119014D01*
X360862D01*
X359025Y118252D01*
X357618Y116846D01*
X357523Y116616D01*
X356148D01*
X355846Y117346D01*
X354439Y118752D01*
X352601Y119514D01*
X350612D01*
X348775Y118752D01*
X348270Y118248D01*
X347025Y118496D01*
X346989Y118582D01*
X345582Y119989D01*
X345352Y120084D01*
Y121459D01*
X346082Y121761D01*
X347241Y122920D01*
X348329Y121831D01*
X350167Y121070D01*
X352156D01*
X353993Y121831D01*
X355400Y123238D01*
X355495Y123468D01*
X356870D01*
X357172Y122738D01*
X358579Y121331D01*
X360417Y120570D01*
X362406D01*
X364244Y121331D01*
X365650Y122738D01*
X366411Y124576D01*
Y126565D01*
X365650Y128402D01*
X364244Y129809D01*
X362406Y130570D01*
X360417D01*
X358579Y129809D01*
X357172Y128402D01*
X357077Y128172D01*
X355702D01*
X355400Y128902D01*
X353993Y130309D01*
X352156Y131070D01*
D02*
G37*
G36*
X467243Y166500D02*
X462757D01*
X458326Y165798D01*
X454060Y164412D01*
X450063Y162375D01*
X446433Y159739D01*
X443261Y156566D01*
X440625Y152937D01*
X438588Y148940D01*
X437202Y144674D01*
X436500Y140243D01*
Y135757D01*
X437202Y131326D01*
X438588Y127060D01*
X440625Y123063D01*
X443261Y119433D01*
X446433Y116261D01*
X450063Y113625D01*
X454060Y111588D01*
X458326Y110202D01*
X462757Y109500D01*
X467243D01*
X471674Y110202D01*
X475940Y111588D01*
X479937Y113625D01*
X483567Y116261D01*
X486739Y119433D01*
X489375Y123063D01*
X491412Y127060D01*
X492798Y131326D01*
X493500Y135757D01*
Y140243D01*
X492798Y144674D01*
X491412Y148940D01*
X489375Y152937D01*
X486739Y156566D01*
X483567Y159739D01*
X479937Y162375D01*
X475940Y164412D01*
X471674Y165798D01*
X467243Y166500D01*
D02*
G37*
G36*
X92000Y124250D02*
X90011D01*
X88173Y123489D01*
X86767Y122082D01*
X86005Y120245D01*
Y118255D01*
X86767Y116418D01*
X88173Y115011D01*
X89254Y114563D01*
Y113189D01*
X88168Y112739D01*
X86761Y111332D01*
X86000Y109495D01*
Y107505D01*
X86761Y105668D01*
X88168Y104261D01*
X90005Y103500D01*
X91995D01*
X93832Y104261D01*
X95239Y105668D01*
X96000Y107505D01*
Y109495D01*
X95239Y111332D01*
X93832Y112739D01*
X92751Y113187D01*
Y114561D01*
X93838Y115011D01*
X95244Y116418D01*
X96005Y118255D01*
Y120245D01*
X95244Y122082D01*
X93838Y123489D01*
X92000Y124250D01*
D02*
G37*
G36*
X56084Y111500D02*
X54095D01*
X52257Y110739D01*
X50851Y109332D01*
X50090Y107495D01*
Y105505D01*
X50851Y103668D01*
X52257Y102261D01*
X54095Y101500D01*
X56084D01*
X57922Y102261D01*
X59328Y103668D01*
X60090Y105505D01*
Y107495D01*
X59328Y109332D01*
X57922Y110739D01*
X56084Y111500D01*
D02*
G37*
G36*
X115245Y109000D02*
X113255D01*
X111418Y108239D01*
X110011Y106832D01*
X109250Y104995D01*
Y103005D01*
X110011Y101168D01*
X111418Y99761D01*
X113255Y99000D01*
X115245D01*
X117082Y99761D01*
X118489Y101168D01*
X119250Y103005D01*
Y104995D01*
X118489Y106832D01*
X117082Y108239D01*
X115245Y109000D01*
D02*
G37*
G36*
X73031Y107261D02*
X71041D01*
X69204Y106500D01*
X67797Y105093D01*
X67036Y103256D01*
Y101267D01*
X67797Y99429D01*
X69204Y98022D01*
X71041Y97261D01*
X73031D01*
X74868Y98022D01*
X76275Y99429D01*
X77036Y101267D01*
Y103256D01*
X76275Y105093D01*
X74868Y106500D01*
X73031Y107261D01*
D02*
G37*
G36*
X130495Y111500D02*
X128505D01*
X126668Y110739D01*
X125261Y109332D01*
X124500Y107495D01*
Y105505D01*
X125261Y103668D01*
X126668Y102261D01*
X128030Y101697D01*
X128040Y100327D01*
X126778Y99804D01*
X125371Y98397D01*
X124610Y96560D01*
Y94571D01*
X125371Y92733D01*
X126778Y91326D01*
X128615Y90565D01*
X130605D01*
X132442Y91326D01*
X133849Y92733D01*
X134610Y94571D01*
Y96560D01*
X133849Y98397D01*
X132442Y99804D01*
X131080Y100368D01*
X131070Y101738D01*
X132332Y102261D01*
X133739Y103668D01*
X134500Y105505D01*
Y107495D01*
X133739Y109332D01*
X132332Y110739D01*
X130495Y111500D01*
D02*
G37*
G36*
X56084Y98504D02*
X54095D01*
X52257Y97743D01*
X50851Y96336D01*
X50090Y94499D01*
Y92509D01*
X50851Y90672D01*
X52257Y89265D01*
X54095Y88504D01*
X56084D01*
X57922Y89265D01*
X59328Y90672D01*
X60090Y92509D01*
Y94499D01*
X59328Y96336D01*
X57922Y97743D01*
X56084Y98504D01*
D02*
G37*
G36*
X42910D02*
X40921D01*
X39083Y97743D01*
X37677Y96336D01*
X36916Y94499D01*
Y92509D01*
X37677Y90672D01*
X39083Y89265D01*
X40921Y88504D01*
X42910D01*
X44748Y89265D01*
X46154Y90672D01*
X46916Y92509D01*
Y94499D01*
X46154Y96336D01*
X44748Y97743D01*
X42910Y98504D01*
D02*
G37*
G36*
X28073D02*
X26083D01*
X24246Y97743D01*
X22839Y96336D01*
X22078Y94499D01*
Y92509D01*
X22839Y90672D01*
X24246Y89265D01*
X26083Y88504D01*
X28073D01*
X29910Y89265D01*
X31317Y90672D01*
X32078Y92509D01*
Y94499D01*
X31317Y96336D01*
X29910Y97743D01*
X28073Y98504D01*
D02*
G37*
G36*
X193900Y74250D02*
X191911D01*
X190073Y73489D01*
X188666Y72082D01*
X188616Y71960D01*
X187259Y72003D01*
X185971Y73291D01*
X184133Y74052D01*
X182144D01*
X180306Y73291D01*
X178900Y71885D01*
X178138Y70047D01*
Y68999D01*
X176868Y68473D01*
X176082Y69259D01*
X174245Y70020D01*
X172255D01*
X170418Y69259D01*
X169011Y67853D01*
X168250Y66015D01*
Y64026D01*
X169011Y62188D01*
X170418Y60782D01*
X172255Y60020D01*
X174245D01*
X176082Y60782D01*
X177489Y62188D01*
X178250Y64026D01*
Y65074D01*
X179520Y65600D01*
X180306Y64814D01*
X182144Y64052D01*
X184133D01*
X185971Y64814D01*
X187377Y66220D01*
X187428Y66342D01*
X188785Y66300D01*
X190073Y65011D01*
X191911Y64250D01*
X193900D01*
X195738Y65011D01*
X197144Y66418D01*
X197905Y68255D01*
Y70245D01*
X197144Y72082D01*
X195738Y73489D01*
X193900Y74250D01*
D02*
G37*
G36*
X162745Y69750D02*
X160755D01*
X158918Y68989D01*
X157511Y67582D01*
X156750Y65745D01*
Y63755D01*
X157511Y61918D01*
X158918Y60511D01*
X160755Y59750D01*
X162745D01*
X164582Y60511D01*
X165989Y61918D01*
X166750Y63755D01*
Y65745D01*
X165989Y67582D01*
X164582Y68989D01*
X162745Y69750D01*
D02*
G37*
G36*
X150495Y68250D02*
X148505D01*
X146668Y67489D01*
X145261Y66082D01*
X144500Y64245D01*
Y62255D01*
X145261Y60418D01*
X146668Y59011D01*
X148505Y58250D01*
X150495D01*
X152332Y59011D01*
X153739Y60418D01*
X154500Y62255D01*
Y64245D01*
X153739Y66082D01*
X152332Y67489D01*
X150495Y68250D01*
D02*
G37*
G36*
X97019Y91500D02*
X92981D01*
X89020Y90712D01*
X85289Y89167D01*
X81932Y86923D01*
X79077Y84068D01*
X76833Y80710D01*
X75288Y76980D01*
X74500Y73019D01*
Y68981D01*
X75288Y65020D01*
X76833Y61290D01*
X79077Y57932D01*
X81932Y55077D01*
X85289Y52833D01*
X89020Y51288D01*
X92981Y50500D01*
X97019D01*
X100980Y51288D01*
X104710Y52833D01*
X108068Y55077D01*
X110923Y57932D01*
X113167Y61290D01*
X114712Y65020D01*
X115500Y68981D01*
Y73019D01*
X114712Y76980D01*
X113167Y80710D01*
X110923Y84068D01*
X108068Y86923D01*
X104710Y89167D01*
X100980Y90712D01*
X97019Y91500D01*
D02*
G37*
G36*
X458639Y63450D02*
X455361D01*
X452195Y62602D01*
X449356Y60963D01*
X447038Y58644D01*
X445398Y55806D01*
X444550Y52639D01*
Y49361D01*
X445398Y46195D01*
X447038Y43355D01*
X449356Y41038D01*
X452195Y39398D01*
X455361Y38550D01*
X458639D01*
X461805Y39398D01*
X464645Y41038D01*
X466963Y43355D01*
X468602Y46195D01*
X469450Y49361D01*
Y52639D01*
X468602Y55806D01*
X466963Y58644D01*
X464645Y60963D01*
X461805Y62602D01*
X458639Y63450D01*
D02*
G37*
G36*
X52639D02*
X49361D01*
X46195Y62602D01*
X43355Y60963D01*
X41038Y58644D01*
X39398Y55806D01*
X38550Y52639D01*
Y49361D01*
X39398Y46195D01*
X41038Y43355D01*
X43355Y41038D01*
X46195Y39398D01*
X49361Y38550D01*
X52639D01*
X55806Y39398D01*
X58644Y41038D01*
X60963Y43355D01*
X62602Y46195D01*
X63450Y49361D01*
Y52639D01*
X62602Y55806D01*
X60963Y58644D01*
X58644Y60963D01*
X55806Y62602D01*
X52639Y63450D01*
D02*
G37*
G36*
X308495Y131250D02*
X306505D01*
X304668Y130489D01*
X303261Y129082D01*
X302500Y127245D01*
Y125255D01*
X303261Y123418D01*
X304668Y122011D01*
X304898Y121916D01*
Y120541D01*
X304168Y120239D01*
X302761Y118832D01*
X302000Y116995D01*
Y115005D01*
X302761Y113168D01*
X304168Y111761D01*
X305054Y111394D01*
Y110019D01*
X303988Y109578D01*
X302581Y108171D01*
X301820Y106333D01*
Y104344D01*
X302581Y102507D01*
X303988Y101100D01*
X304218Y101005D01*
Y99630D01*
X303488Y99328D01*
X302081Y97921D01*
X301320Y96083D01*
Y94094D01*
X302081Y92256D01*
X303488Y90850D01*
X304967Y90237D01*
X305094Y88919D01*
X305093Y88915D01*
X304668Y88739D01*
X303261Y87332D01*
X302500Y85494D01*
Y83505D01*
X303261Y81668D01*
X304668Y80261D01*
X304898Y80166D01*
Y78791D01*
X304168Y78489D01*
X302761Y77082D01*
X302000Y75245D01*
Y73255D01*
X302761Y71418D01*
X304168Y70011D01*
X305054Y69644D01*
Y68269D01*
X303988Y67828D01*
X302581Y66421D01*
X301820Y64583D01*
Y62594D01*
X302581Y60757D01*
X303988Y59350D01*
X304218Y59255D01*
Y57880D01*
X303488Y57578D01*
X302081Y56171D01*
X301320Y54333D01*
Y52344D01*
X302081Y50507D01*
X303488Y49100D01*
X303294Y47806D01*
X303000Y47095D01*
Y45106D01*
X303761Y43268D01*
X305168Y41862D01*
X305398Y41766D01*
Y40392D01*
X304668Y40089D01*
X303261Y38682D01*
X302500Y36845D01*
Y34856D01*
X303261Y33018D01*
X304668Y31611D01*
X306505Y30850D01*
X308495D01*
X310332Y31611D01*
X311739Y33018D01*
X312500Y34856D01*
Y36845D01*
X311739Y38682D01*
X310332Y40089D01*
X310102Y40184D01*
Y41559D01*
X310832Y41862D01*
X312239Y43268D01*
X313000Y45106D01*
Y47095D01*
X312239Y48932D01*
X310832Y50339D01*
X310571Y50447D01*
X310559Y50507D01*
X311320Y52344D01*
Y54333D01*
X310559Y56171D01*
X309152Y57578D01*
X308922Y57673D01*
Y59048D01*
X309652Y59350D01*
X311059Y60757D01*
X311820Y62594D01*
Y64583D01*
X311059Y66421D01*
X309652Y67828D01*
X308766Y68195D01*
Y69570D01*
X309832Y70011D01*
X311239Y71418D01*
X312000Y73255D01*
Y75245D01*
X311239Y77082D01*
X309832Y78489D01*
X309602Y78584D01*
Y79959D01*
X310332Y80261D01*
X311739Y81668D01*
X312500Y83505D01*
Y85494D01*
X311739Y87332D01*
X310332Y88739D01*
X308853Y89351D01*
X308726Y90670D01*
X308727Y90674D01*
X309152Y90850D01*
X310559Y92256D01*
X311320Y94094D01*
Y96083D01*
X310559Y97921D01*
X309152Y99328D01*
X308922Y99423D01*
Y100798D01*
X309652Y101100D01*
X311059Y102507D01*
X311820Y104344D01*
Y106333D01*
X311059Y108171D01*
X309652Y109578D01*
X308766Y109945D01*
Y111320D01*
X309832Y111761D01*
X311239Y113168D01*
X312000Y115005D01*
Y116995D01*
X311239Y118832D01*
X309832Y120239D01*
X309602Y120334D01*
Y121709D01*
X310332Y122011D01*
X311739Y123418D01*
X312500Y125255D01*
Y127245D01*
X311739Y129082D01*
X310332Y130489D01*
X308495Y131250D01*
D02*
G37*
G36*
X321245Y131000D02*
X319255D01*
X317418Y130239D01*
X316011Y128832D01*
X315250Y126995D01*
Y125005D01*
X316011Y123168D01*
X317418Y121761D01*
X317648Y121666D01*
Y120291D01*
X316918Y119989D01*
X315511Y118582D01*
X314750Y116745D01*
Y114755D01*
X315511Y112918D01*
X316918Y111511D01*
X317804Y111144D01*
Y109769D01*
X316738Y109328D01*
X315331Y107921D01*
X314570Y106083D01*
Y104094D01*
X315331Y102256D01*
X316738Y100850D01*
X316968Y100755D01*
Y99380D01*
X316238Y99078D01*
X314831Y97671D01*
X314070Y95833D01*
Y93844D01*
X314831Y92007D01*
X316238Y90600D01*
X317717Y89987D01*
X317844Y88669D01*
X317843Y88665D01*
X317418Y88489D01*
X316011Y87082D01*
X315250Y85245D01*
Y83255D01*
X316011Y81418D01*
X317418Y80011D01*
X317648Y79916D01*
Y78541D01*
X316918Y78239D01*
X315511Y76832D01*
X314750Y74995D01*
Y73005D01*
X315511Y71168D01*
X316918Y69761D01*
X317804Y69394D01*
Y68019D01*
X316738Y67578D01*
X315331Y66171D01*
X314570Y64333D01*
Y62344D01*
X315331Y60507D01*
X316738Y59100D01*
X316968Y59005D01*
Y57630D01*
X316238Y57328D01*
X314831Y55921D01*
X314070Y54083D01*
Y52094D01*
X314831Y50257D01*
X316238Y48850D01*
X316044Y47555D01*
X315750Y46845D01*
Y44856D01*
X316511Y43018D01*
X317918Y41611D01*
X318148Y41516D01*
Y40142D01*
X317418Y39839D01*
X316011Y38433D01*
X315250Y36595D01*
Y34606D01*
X316011Y32768D01*
X317418Y31361D01*
X319255Y30600D01*
X321245D01*
X323082Y31361D01*
X324489Y32768D01*
X325250Y34606D01*
Y36595D01*
X324489Y38433D01*
X323082Y39839D01*
X322852Y39934D01*
Y41309D01*
X323582Y41611D01*
X324989Y43018D01*
X325750Y44856D01*
Y46845D01*
X324989Y48683D01*
X323582Y50089D01*
X323776Y51384D01*
X324070Y52094D01*
Y54083D01*
X323309Y55921D01*
X321902Y57328D01*
X321672Y57423D01*
Y58798D01*
X322402Y59100D01*
X323809Y60507D01*
X324570Y62344D01*
Y64333D01*
X323809Y66171D01*
X322402Y67578D01*
X321516Y67945D01*
Y69320D01*
X322582Y69761D01*
X323989Y71168D01*
X324750Y73005D01*
Y74995D01*
X323989Y76832D01*
X322582Y78239D01*
X322352Y78334D01*
Y79709D01*
X323082Y80011D01*
X324489Y81418D01*
X325250Y83255D01*
Y85245D01*
X324489Y87082D01*
X323082Y88489D01*
X321603Y89101D01*
X321476Y90420D01*
X321477Y90424D01*
X321902Y90600D01*
X323309Y92007D01*
X324070Y93844D01*
Y95833D01*
X323309Y97671D01*
X321902Y99078D01*
X321672Y99173D01*
Y100548D01*
X322402Y100850D01*
X323809Y102256D01*
X324570Y104094D01*
Y106083D01*
X323809Y107921D01*
X322402Y109328D01*
X321516Y109695D01*
Y111069D01*
X322582Y111511D01*
X323989Y112918D01*
X324750Y114755D01*
Y116745D01*
X323989Y118582D01*
X322582Y119989D01*
X322352Y120084D01*
Y121459D01*
X323082Y121761D01*
X324489Y123168D01*
X325250Y125005D01*
Y126995D01*
X324489Y128832D01*
X323082Y130239D01*
X321245Y131000D01*
D02*
G37*
G36*
X332688Y130554D02*
X330699D01*
X328861Y129793D01*
X327455Y128387D01*
X326693Y126549D01*
Y124560D01*
X327455Y122722D01*
X328861Y121316D01*
X329091Y121220D01*
Y119846D01*
X328361Y119543D01*
X326955Y118137D01*
X326194Y116299D01*
Y114310D01*
X326955Y112472D01*
X328361Y111066D01*
X329248Y110698D01*
Y109324D01*
X328181Y108882D01*
X326775Y107476D01*
X326013Y105638D01*
Y103649D01*
X326775Y101811D01*
X328181Y100404D01*
X328411Y100309D01*
Y98934D01*
X327681Y98632D01*
X326275Y97226D01*
X325513Y95388D01*
Y93399D01*
X326275Y91561D01*
X327681Y90154D01*
X329160Y89542D01*
X329287Y88223D01*
X329287Y88219D01*
X328861Y88043D01*
X327455Y86637D01*
X326693Y84799D01*
Y82810D01*
X327455Y80972D01*
X328861Y79566D01*
X329091Y79470D01*
Y78096D01*
X328361Y77793D01*
X326955Y76387D01*
X326194Y74549D01*
Y72560D01*
X326955Y70722D01*
X328361Y69316D01*
X329248Y68948D01*
Y67574D01*
X328181Y67132D01*
X326775Y65725D01*
X326013Y63888D01*
Y61899D01*
X326775Y60061D01*
X328181Y58654D01*
X328411Y58559D01*
Y57184D01*
X327681Y56882D01*
X326275Y55476D01*
X325513Y53638D01*
Y51649D01*
X326275Y49811D01*
X327681Y48404D01*
X327488Y47110D01*
X327193Y46399D01*
Y44410D01*
X327955Y42572D01*
X329361Y41166D01*
X329591Y41070D01*
Y39696D01*
X328861Y39393D01*
X327455Y37987D01*
X326693Y36149D01*
Y34160D01*
X327455Y32322D01*
X328861Y30916D01*
X330699Y30155D01*
X332688D01*
X334526Y30916D01*
X335932Y32322D01*
X336693Y34160D01*
Y36149D01*
X335932Y37987D01*
X334526Y39393D01*
X334296Y39489D01*
Y40863D01*
X335026Y41166D01*
X336432Y42572D01*
X337193Y44410D01*
Y46399D01*
X336432Y48237D01*
X335026Y49643D01*
X335219Y50938D01*
X335513Y51649D01*
Y53638D01*
X334752Y55476D01*
X333346Y56882D01*
X333116Y56977D01*
Y58352D01*
X333846Y58654D01*
X335252Y60061D01*
X336013Y61899D01*
Y63888D01*
X335252Y65725D01*
X333846Y67132D01*
X332959Y67499D01*
Y68874D01*
X334026Y69316D01*
X335432Y70722D01*
X336194Y72560D01*
Y74549D01*
X335432Y76387D01*
X334026Y77793D01*
X333796Y77888D01*
Y79263D01*
X334526Y79566D01*
X335932Y80972D01*
X336693Y82810D01*
Y84799D01*
X335932Y86637D01*
X334526Y88043D01*
X333047Y88656D01*
X332920Y89974D01*
X332920Y89978D01*
X333346Y90154D01*
X334752Y91561D01*
X335513Y93399D01*
Y95388D01*
X334752Y97226D01*
X333346Y98632D01*
X333116Y98727D01*
Y100102D01*
X333846Y100404D01*
X335252Y101811D01*
X336013Y103649D01*
Y105638D01*
X335252Y107476D01*
X333846Y108882D01*
X332959Y109249D01*
Y110624D01*
X334026Y111066D01*
X335432Y112472D01*
X336194Y114310D01*
Y116299D01*
X335432Y118137D01*
X334026Y119543D01*
X333796Y119639D01*
Y121013D01*
X334526Y121316D01*
X335932Y122722D01*
X336693Y124560D01*
Y126549D01*
X335932Y128387D01*
X334526Y129793D01*
X332688Y130554D01*
D02*
G37*
G36*
X408019Y61500D02*
X403981D01*
X400020Y60712D01*
X396290Y59167D01*
X392932Y56923D01*
X390077Y54068D01*
X387833Y50710D01*
X386288Y46980D01*
X385500Y43019D01*
Y38981D01*
X386288Y35020D01*
X387833Y31290D01*
X390077Y27932D01*
X392932Y25077D01*
X396290Y22833D01*
X400020Y21288D01*
X403981Y20500D01*
X408019D01*
X411980Y21288D01*
X415710Y22833D01*
X419068Y25077D01*
X421923Y27932D01*
X424167Y31290D01*
X425712Y35020D01*
X426500Y38981D01*
Y43019D01*
X425712Y46980D01*
X424167Y50710D01*
X421923Y54068D01*
X419068Y56923D01*
X415710Y59167D01*
X411980Y60712D01*
X408019Y61500D01*
D02*
G37*
%LPD*%
D76*
X34250Y179000D02*
D03*
D77*
X59650D02*
D03*
D78*
X192000Y484000D02*
D03*
X51000Y457000D02*
D03*
X457000Y51000D02*
D03*
Y457000D02*
D03*
X132000Y484000D02*
D03*
X102000D02*
D03*
X72000D02*
D03*
X457000Y254000D02*
D03*
X51000Y51000D02*
D03*
X162000Y484000D02*
D03*
D79*
X465000Y138000D02*
D03*
Y349000D02*
D03*
D80*
X315000Y203311D02*
D03*
X241500Y478750D02*
D03*
X220968Y339000D02*
D03*
X349911Y39320D02*
D03*
X350161Y52070D02*
D03*
X350607Y63513D02*
D03*
X350161Y75070D02*
D03*
X360411Y74570D02*
D03*
X360857Y63014D02*
D03*
X360411Y51570D02*
D03*
X360161Y38820D02*
D03*
X350911Y90320D02*
D03*
X351161Y103070D02*
D03*
X351607Y114514D02*
D03*
X351161Y126070D02*
D03*
X361411Y125570D02*
D03*
X361857Y114014D02*
D03*
X361411Y102570D02*
D03*
X361161Y89820D02*
D03*
X308000Y46100D02*
D03*
X320750Y45850D02*
D03*
X332193Y45405D02*
D03*
X343750Y45850D02*
D03*
X343250Y35600D02*
D03*
X331693Y35155D02*
D03*
X320250Y35600D02*
D03*
X307500Y35850D02*
D03*
Y84500D02*
D03*
X320250Y84250D02*
D03*
X331693Y83804D02*
D03*
X343250Y84250D02*
D03*
X342750Y74000D02*
D03*
X331194Y73554D02*
D03*
X319750Y74000D02*
D03*
X307000Y74250D02*
D03*
X306320Y53339D02*
D03*
X319070Y53089D02*
D03*
X330513Y52643D02*
D03*
X342070Y53089D02*
D03*
X342570Y63339D02*
D03*
X331013Y62893D02*
D03*
X319570Y63339D02*
D03*
X306820Y63589D02*
D03*
Y105339D02*
D03*
X319570Y105089D02*
D03*
X331013Y104643D02*
D03*
X342570Y105089D02*
D03*
X342070Y94839D02*
D03*
X330513Y94393D02*
D03*
X319070Y94839D02*
D03*
X306320Y95089D02*
D03*
X307000Y116000D02*
D03*
X319750Y115750D02*
D03*
X331194Y115304D02*
D03*
X342750Y115750D02*
D03*
X343250Y126000D02*
D03*
X331693Y125554D02*
D03*
X320250Y126000D02*
D03*
X307500Y126250D02*
D03*
X192905Y69250D02*
D03*
X183138Y69052D02*
D03*
X173250Y65020D02*
D03*
X161750Y64750D02*
D03*
X149500Y63250D02*
D03*
X234398Y422690D02*
D03*
X223373Y415288D02*
D03*
X298715Y489190D02*
D03*
X351500Y488750D02*
D03*
X445113Y472750D02*
D03*
X475000Y447750D02*
D03*
X331500Y400274D02*
D03*
X327000Y392924D02*
D03*
X342703Y406495D02*
D03*
X206542Y332843D02*
D03*
X193292Y330805D02*
D03*
X145000Y264000D02*
D03*
X156752Y276869D02*
D03*
X83952Y262552D02*
D03*
X17462Y347587D02*
D03*
X363500Y449682D02*
D03*
X241197Y308750D02*
D03*
X285250Y446030D02*
D03*
X372500Y440000D02*
D03*
X440352Y374949D02*
D03*
X294500Y454750D02*
D03*
X270921Y437500D02*
D03*
X267761Y319250D02*
D03*
X172000Y147750D02*
D03*
X158750Y132850D02*
D03*
X52118Y197290D02*
D03*
X65473Y198873D02*
D03*
X65619Y215500D02*
D03*
X66659Y224000D02*
D03*
X87000Y475250D02*
D03*
X117080Y493963D02*
D03*
X177000Y492750D02*
D03*
X209500Y489750D02*
D03*
X444999Y421418D02*
D03*
X69000Y463250D02*
D03*
X289250Y269500D02*
D03*
X343677Y360775D02*
D03*
X391028Y361264D02*
D03*
X354750Y339500D02*
D03*
X363284Y389088D02*
D03*
X259492Y353693D02*
D03*
X274414Y352344D02*
D03*
X334750Y326000D02*
D03*
X297250Y385500D02*
D03*
X228424Y209744D02*
D03*
X224129Y188721D02*
D03*
X243500Y244381D02*
D03*
X212000Y174955D02*
D03*
X159750Y177787D02*
D03*
X171400Y173000D02*
D03*
X258939Y182705D02*
D03*
X243939Y182955D02*
D03*
X270189Y187644D02*
D03*
X258939Y209744D02*
D03*
X243939D02*
D03*
X279206Y190705D02*
D03*
X315250Y392363D02*
D03*
X345269Y393919D02*
D03*
X169161Y102103D02*
D03*
X183138D02*
D03*
X172498Y113250D02*
D03*
X95610Y353378D02*
D03*
X184407Y173689D02*
D03*
X146750Y230310D02*
D03*
X350250Y211521D02*
D03*
X344750Y243000D02*
D03*
X332000D02*
D03*
X243500Y257561D02*
D03*
X293674Y244381D02*
D03*
X206956Y397805D02*
D03*
X207706Y432800D02*
D03*
X175750D02*
D03*
X51500Y390689D02*
D03*
X103750Y358378D02*
D03*
X142000Y359750D02*
D03*
X109250Y377668D02*
D03*
X139750Y463508D02*
D03*
X17785Y397960D02*
D03*
X17500Y388019D02*
D03*
Y377710D02*
D03*
Y367710D02*
D03*
Y357460D02*
D03*
X8744Y354901D02*
D03*
X244245Y292311D02*
D03*
X393250Y242500D02*
D03*
X272892Y294750D02*
D03*
X55967Y354628D02*
D03*
X27078Y93504D02*
D03*
X129610Y95565D02*
D03*
X55090Y93504D02*
D03*
X91000Y108500D02*
D03*
X391579Y185091D02*
D03*
X403000Y173750D02*
D03*
Y263500D02*
D03*
X414482Y274431D02*
D03*
X273500Y244381D02*
D03*
X258000D02*
D03*
Y292250D02*
D03*
X363962Y297432D02*
D03*
X232250Y291385D02*
D03*
X264500Y375775D02*
D03*
X375750Y322588D02*
D03*
X145319Y249000D02*
D03*
X160000Y186500D02*
D03*
X84365Y251500D02*
D03*
X22702Y246500D02*
D03*
X52108Y254060D02*
D03*
X102727Y162527D02*
D03*
X66500D02*
D03*
X77704D02*
D03*
X115250D02*
D03*
X142000Y178086D02*
D03*
X130429Y181250D02*
D03*
X114250Y104000D02*
D03*
X72036Y102261D02*
D03*
X41916Y93504D02*
D03*
X55090Y106500D02*
D03*
X91005Y119250D02*
D03*
X129500Y106500D02*
D03*
X403000Y185091D02*
D03*
X403000Y274431D02*
D03*
M02*
